(kicad_pcb
	(version 20260206)
	(generator "pcbnew")
	(generator_version "10.0")
	(general
		(thickness 1.6)
		(legacy_teardrops no)
	)
	(paper "A4")
	(title_block
		(title "12092022_DA0F0TFB6D0_F0T_FAN_BOARD_MP5048_D_brd_v02_OCP.brd")
		(comment 1 "Grand Teton / footprints 141-147 of 924")
	)
	(layers
		(0 "F.Cu" signal "TOP")
		(4 "In1.Cu" signal "GND")
		(6 "In2.Cu" signal "IN1")
		(8 "In3.Cu" signal "IN2")
		(10 "In4.Cu" signal "GND1")
		(2 "B.Cu" signal "BOTTOM")
		(9 "F.Adhes" user "F.Adhesive")
		(11 "B.Adhes" user "B.Adhesive")
		(13 "F.Paste" user "Package Geometry/Pastemask Top")
		(15 "B.Paste" user "Package Geometry/Pastemask Bottom")
		(5 "F.SilkS" user "Ref Des/Silkscreen Top")
		(7 "B.SilkS" user "Ref Des/Silkscreen Bottom")
		(1 "F.Mask" user "Board Geometry/Soldermask Top")
		(3 "B.Mask" user "Board Geometry/Soldermask Bottom")
		(17 "Dwgs.User" user "User.Drawings")
		(19 "Cmts.User" user "User.Comments")
		(21 "Eco1.User" user "User.Eco1")
		(23 "Eco2.User" user "User.Eco2")
		(25 "Edge.Cuts" user "Board Geometry/Outline")
		(27 "Margin" user)
		(31 "F.CrtYd" user "Package Geometry/Place Bound Top")
		(29 "B.CrtYd" user "Package Geometry/Place Bound Bottom")
		(35 "F.Fab" user "Ref Des/Assembly Top")
		(33 "B.Fab" user "Ref Des/Assembly Bottom")
	)
	(footprint ""
		(layer "F.Cu")
		(at 36.703 -18.542 -90)
		(property "Reference" "R5406"
			(at 0 0 270)
			(layer "F.SilkS")
			(hide yes)
			(effects
				(font
					(size 1.27 1.27)
				)
			)
		)
		(property "Value" ""
			(at 0 0 270)
			(layer "F.Fab")
			(effects
				(font
					(size 1.27 1.27)
				)
			)
		)
		(duplicate_pad_numbers_are_jumpers no)
		(fp_line
			(start -0.7874 0.4064)
			(end -0.7874 -0.4064)
			(stroke
				(width 0.1524)
				(type default)
			)
			(layer "F.SilkS")
		)
		(fp_line
			(start 0.7874 0.4064)
			(end -0.7874 0.4064)
			(stroke
				(width 0.1524)
				(type default)
			)
			(layer "F.SilkS")
		)
		(fp_line
			(start -0.7874 -0.4064)
			(end 0.7874 -0.4064)
			(stroke
				(width 0.1524)
				(type default)
			)
			(layer "F.SilkS")
		)
		(fp_line
			(start 0.7874 -0.4064)
			(end 0.7874 0.4064)
			(stroke
				(width 0.1524)
				(type default)
			)
			(layer "F.SilkS")
		)
		(fp_line
			(start -0.67945 0.3048)
			(end -0.67945 -0.305054)
			(stroke
				(width 0.1)
				(type default)
			)
			(layer "F.Fab")
		)
		(fp_line
			(start -0.12065 0.3048)
			(end -0.67945 0.3048)
			(stroke
				(width 0.1)
				(type default)
			)
			(layer "F.Fab")
		)
		(fp_line
			(start 0.120396 0.3048)
			(end 0.120396 0.2794)
			(stroke
				(width 0.1)
				(type default)
			)
			(layer "F.Fab")
		)
		(fp_line
			(start 0.67945 0.3048)
			(end 0.120396 0.3048)
			(stroke
				(width 0.1)
				(type default)
			)
			(layer "F.Fab")
		)
		(fp_line
			(start -0.12065 0.2794)
			(end -0.12065 0.3048)
			(stroke
				(width 0.1)
				(type default)
			)
			(layer "F.Fab")
		)
		(fp_line
			(start 0.120396 0.2794)
			(end -0.12065 0.2794)
			(stroke
				(width 0.1)
				(type default)
			)
			(layer "F.Fab")
		)
		(fp_line
			(start -0.12065 -0.2794)
			(end 0.12065 -0.2794)
			(stroke
				(width 0.1)
				(type default)
			)
			(layer "F.Fab")
		)
		(fp_line
			(start 0.12065 -0.2794)
			(end 0.12065 -0.3048)
			(stroke
				(width 0.1)
				(type default)
			)
			(layer "F.Fab")
		)
		(fp_line
			(start 0.12065 -0.3048)
			(end 0.67945 -0.3048)
			(stroke
				(width 0.1)
				(type default)
			)
			(layer "F.Fab")
		)
		(fp_line
			(start 0.67945 -0.3048)
			(end 0.67945 0.3048)
			(stroke
				(width 0.1)
				(type default)
			)
			(layer "F.Fab")
		)
		(fp_line
			(start -0.67945 -0.305054)
			(end -0.12065 -0.305054)
			(stroke
				(width 0.1)
				(type default)
			)
			(layer "F.Fab")
		)
		(fp_line
			(start -0.12065 -0.305054)
			(end -0.12065 -0.2794)
			(stroke
				(width 0.1)
				(type default)
			)
			(layer "F.Fab")
		)
		(pad "1" smd rect
			(at -0.40005 0 90)
			(size 0.4572 0.508)
			(layers "F.Cu" "F.Mask" "F.Paste")
			(net "FAN_3_OK_LED_R_N")
		)
		(pad "2" smd rect
			(at 0.40005 0 90)
			(size 0.4572 0.508)
			(layers "F.Cu" "F.Mask" "F.Paste")
			(net "FAN_3_OK_R_LED_N")
		)
	)
	(footprint ""
		(layer "F.Cu")
		(at 37.719 -14.351 90)
		(property "Reference" "D283"
			(at -4.064 0.02667 90)
			(unlocked yes)
			(layer "F.SilkS")
			(effects
				(font
					(size 0.7874 0.5842)
					(thickness 0.1524)
				)
				(justify left)
			)
		)
		(property "Value" ""
			(at 0 0 90)
			(layer "F.Fab")
			(effects
				(font
					(size 1.27 1.27)
				)
			)
		)
		(duplicate_pad_numbers_are_jumpers no)
		(fp_line
			(start 0.94488 -0.450088)
			(end -0.854964 -0.450088)
			(stroke
				(width 0.1524)
				(type default)
			)
			(layer "F.SilkS")
		)
		(fp_line
			(start -0.854964 -0.450088)
			(end -0.854964 0.450088)
			(stroke
				(width 0.1524)
				(type default)
			)
			(layer "F.SilkS")
		)
		(fp_line
			(start 0.870458 -0.2794)
			(end 0.845058 0.4064)
			(stroke
				(width 0.1524)
				(type default)
			)
			(layer "F.SilkS")
		)
		(fp_line
			(start 0.845058 0.4064)
			(end 0.845058 -0.381)
			(stroke
				(width 0.1524)
				(type default)
			)
			(layer "F.SilkS")
		)
		(fp_line
			(start 0.94488 0.450088)
			(end 0.94488 -0.450088)
			(stroke
				(width 0.1524)
				(type default)
			)
			(layer "F.SilkS")
		)
		(fp_line
			(start -0.854964 0.450088)
			(end 0.925068 0.450088)
			(stroke
				(width 0.1524)
				(type default)
			)
			(layer "F.SilkS")
		)
		(fp_line
			(start 0.54991 -0.350012)
			(end -0.54991 -0.350012)
			(stroke
				(width 0.1)
				(type default)
			)
			(layer "F.Fab")
		)
		(fp_line
			(start -0.54991 -0.350012)
			(end -0.54991 0.350012)
			(stroke
				(width 0.1)
				(type default)
			)
			(layer "F.Fab")
		)
		(fp_line
			(start 0.54991 0.350012)
			(end 0.54991 -0.350012)
			(stroke
				(width 0.1)
				(type default)
			)
			(layer "F.Fab")
		)
		(fp_line
			(start -0.54991 0.350012)
			(end 0.54991 0.350012)
			(stroke
				(width 0.1)
				(type default)
			)
			(layer "F.Fab")
		)
		(fp_text user "-"
			(at 1.27 1.36525 270)
			(unlocked yes)
			(layer "F.SilkS")
			(effects
				(font
					(size 1.905 1.4224)
					(thickness 0.1524)
				)
				(justify left)
			)
		)
		(fp_text user "+"
			(at 0.254 1.36525 270)
			(unlocked yes)
			(layer "F.SilkS")
			(effects
				(font
					(size 1.905 1.4224)
					(thickness 0.1524)
				)
				(justify left)
			)
		)
		(fp_text user "-"
			(at 2.48539 0.239014 270)
			(unlocked yes)
			(layer "F.Fab")
			(effects
				(font
					(size 1.905 1.4224)
					(thickness 0.1524)
				)
				(justify left)
			)
		)
		(fp_text user "+"
			(at -0.808228 0.239014 270)
			(unlocked yes)
			(layer "F.Fab")
			(effects
				(font
					(size 1.905 1.4224)
					(thickness 0.1524)
				)
				(justify left)
			)
		)
		(pad "A" smd rect
			(at -0.424942 0 90)
			(size 0.5588 0.6096)
			(layers "F.Cu" "F.Mask" "F.Paste")
			(net "GND")
		)
		(pad "C" smd rect
			(at 0.424942 0 270)
			(size 0.5588 0.6096)
			(layers "F.Cu" "F.Mask" "F.Paste")
			(net "FAN_3_TACH_OL_D")
		)
	)
	(footprint ""
		(layer "F.Cu")
		(at 19.177 -211.836)
		(property "Reference" "C2047"
			(at 0 0 0)
			(layer "F.SilkS")
			(hide yes)
			(effects
				(font
					(size 1.27 1.27)
				)
			)
		)
		(property "Value" ""
			(at 0 0 0)
			(layer "F.Fab")
			(effects
				(font
					(size 1.27 1.27)
				)
			)
		)
		(duplicate_pad_numbers_are_jumpers no)
		(fp_line
			(start -0.7874 -0.4064)
			(end 0.7874 -0.4064)
			(stroke
				(width 0.1524)
				(type default)
			)
			(layer "F.SilkS")
		)
		(fp_line
			(start -0.7874 0.4064)
			(end -0.7874 -0.4064)
			(stroke
				(width 0.1524)
				(type default)
			)
			(layer "F.SilkS")
		)
		(fp_line
			(start 0.7874 -0.4064)
			(end 0.7874 0.4064)
			(stroke
				(width 0.1524)
				(type default)
			)
			(layer "F.SilkS")
		)
		(fp_line
			(start 0.7874 0.4064)
			(end -0.7874 0.4064)
			(stroke
				(width 0.1524)
				(type default)
			)
			(layer "F.SilkS")
		)
		(fp_line
			(start -0.67945 -0.305054)
			(end -0.12065 -0.305054)
			(stroke
				(width 0.1)
				(type default)
			)
			(layer "F.Fab")
		)
		(fp_line
			(start -0.67945 0.3048)
			(end -0.67945 -0.305054)
			(stroke
				(width 0.1)
				(type default)
			)
			(layer "F.Fab")
		)
		(fp_line
			(start -0.12065 -0.305054)
			(end -0.12065 -0.2794)
			(stroke
				(width 0.1)
				(type default)
			)
			(layer "F.Fab")
		)
		(fp_line
			(start -0.12065 -0.2794)
			(end 0.12065 -0.2794)
			(stroke
				(width 0.1)
				(type default)
			)
			(layer "F.Fab")
		)
		(fp_line
			(start -0.12065 0.2794)
			(end -0.12065 0.3048)
			(stroke
				(width 0.1)
				(type default)
			)
			(layer "F.Fab")
		)
		(fp_line
			(start -0.12065 0.3048)
			(end -0.67945 0.3048)
			(stroke
				(width 0.1)
				(type default)
			)
			(layer "F.Fab")
		)
		(fp_line
			(start 0.120396 0.2794)
			(end -0.12065 0.2794)
			(stroke
				(width 0.1)
				(type default)
			)
			(layer "F.Fab")
		)
		(fp_line
			(start 0.120396 0.3048)
			(end 0.120396 0.2794)
			(stroke
				(width 0.1)
				(type default)
			)
			(layer "F.Fab")
		)
		(fp_line
			(start 0.12065 -0.3048)
			(end 0.67945 -0.3048)
			(stroke
				(width 0.1)
				(type default)
			)
			(layer "F.Fab")
		)
		(fp_line
			(start 0.12065 -0.2794)
			(end 0.12065 -0.3048)
			(stroke
				(width 0.1)
				(type default)
			)
			(layer "F.Fab")
		)
		(fp_line
			(start 0.67945 -0.3048)
			(end 0.67945 0.3048)
			(stroke
				(width 0.1)
				(type default)
			)
			(layer "F.Fab")
		)
		(fp_line
			(start 0.67945 0.3048)
			(end 0.120396 0.3048)
			(stroke
				(width 0.1)
				(type default)
			)
			(layer "F.Fab")
		)
		(pad "1" smd circle
			(at -0.40005 0)
			(size 0 0)
			(layers "F.Cu" "F.Mask" "F.Paste")
			(net "FAN_6_TACH_OL_R")
		)
		(pad "2" smd circle
			(at 0.40005 0)
			(size 0 0)
			(layers "F.Cu" "F.Mask" "F.Paste")
			(net "GND")
		)
	)
	(footprint ""
		(layer "F.Cu")
		(at 37.211 -194.691)
		(property "Reference" "D271"
			(at 2.286 0.436626 0)
			(unlocked yes)
			(layer "F.SilkS")
			(effects
				(font
					(size 0.7874 0.5842)
					(thickness 0.1524)
				)
				(justify left)
			)
		)
		(property "Value" ""
			(at 0 0 0)
			(layer "F.Fab")
			(effects
				(font
					(size 1.27 1.27)
				)
			)
		)
		(duplicate_pad_numbers_are_jumpers no)
		(fp_line
			(start -0.854964 -0.450088)
			(end -0.854964 0.450088)
			(stroke
				(width 0.1524)
				(type default)
			)
			(layer "F.SilkS")
		)
		(fp_line
			(start -0.854964 0.450088)
			(end 0.925068 0.450088)
			(stroke
				(width 0.1524)
				(type default)
			)
			(layer "F.SilkS")
		)
		(fp_line
			(start 0.845058 0.4064)
			(end 0.845058 -0.381)
			(stroke
				(width 0.1524)
				(type default)
			)
			(layer "F.SilkS")
		)
		(fp_line
			(start 0.870458 -0.2794)
			(end 0.845058 0.4064)
			(stroke
				(width 0.1524)
				(type default)
			)
			(layer "F.SilkS")
		)
		(fp_line
			(start 0.94488 -0.450088)
			(end -0.854964 -0.450088)
			(stroke
				(width 0.1524)
				(type default)
			)
			(layer "F.SilkS")
		)
		(fp_line
			(start 0.94488 0.450088)
			(end 0.94488 -0.450088)
			(stroke
				(width 0.1524)
				(type default)
			)
			(layer "F.SilkS")
		)
		(fp_line
			(start -0.54991 -0.350012)
			(end -0.54991 0.350012)
			(stroke
				(width 0.1)
				(type default)
			)
			(layer "F.Fab")
		)
		(fp_line
			(start -0.54991 0.350012)
			(end 0.54991 0.350012)
			(stroke
				(width 0.1)
				(type default)
			)
			(layer "F.Fab")
		)
		(fp_line
			(start 0.54991 -0.350012)
			(end -0.54991 -0.350012)
			(stroke
				(width 0.1)
				(type default)
			)
			(layer "F.Fab")
		)
		(fp_line
			(start 0.54991 0.350012)
			(end 0.54991 -0.350012)
			(stroke
				(width 0.1)
				(type default)
			)
			(layer "F.Fab")
		)
		(fp_text user "+"
			(at -0.635 0.251206 180)
			(unlocked yes)
			(layer "F.SilkS")
			(effects
				(font
					(size 1.905 1.4224)
					(thickness 0.1524)
				)
				(justify left)
			)
		)
		(fp_text user "-"
			(at 2.159 0.251206 180)
			(unlocked yes)
			(layer "F.SilkS")
			(effects
				(font
					(size 1.905 1.4224)
					(thickness 0.1524)
				)
				(justify left)
			)
		)
		(fp_text user "+"
			(at -0.808228 0.239014 180)
			(unlocked yes)
			(layer "F.Fab")
			(effects
				(font
					(size 1.905 1.4224)
					(thickness 0.1524)
				)
				(justify left)
			)
		)
		(fp_text user "-"
			(at 2.48539 0.239014 180)
			(unlocked yes)
			(layer "F.Fab")
			(effects
				(font
					(size 1.905 1.4224)
					(thickness 0.1524)
				)
				(justify left)
			)
		)
		(pad "A" smd rect
			(at -0.424942 0)
			(size 0.5588 0.6096)
			(layers "F.Cu" "F.Mask" "F.Paste")
			(net "GND")
		)
		(pad "C" smd rect
			(at 0.424942 0 180)
			(size 0.5588 0.6096)
			(layers "F.Cu" "F.Mask" "F.Paste")
			(net "FAN_1_TACH_OL_D")
		)
	)
	(footprint ""
		(layer "F.Cu")
		(at 16.129 -258.572 90)
		(property "Reference" "PR72"
			(at 0 0 90)
			(layer "F.SilkS")
			(hide yes)
			(effects
				(font
					(size 1.27 1.27)
				)
			)
		)
		(property "Value" ""
			(at 0 0 90)
			(layer "F.Fab")
			(effects
				(font
					(size 1.27 1.27)
				)
			)
		)
		(duplicate_pad_numbers_are_jumpers no)
		(fp_line
			(start 0.7874 -0.4064)
			(end 0.7874 0.4064)
			(stroke
				(width 0.1524)
				(type default)
			)
			(layer "F.SilkS")
		)
		(fp_line
			(start -0.7874 -0.4064)
			(end 0.7874 -0.4064)
			(stroke
				(width 0.1524)
				(type default)
			)
			(layer "F.SilkS")
		)
		(fp_line
			(start 0.7874 0.4064)
			(end -0.7874 0.4064)
			(stroke
				(width 0.1524)
				(type default)
			)
			(layer "F.SilkS")
		)
		(fp_line
			(start -0.7874 0.4064)
			(end -0.7874 -0.4064)
			(stroke
				(width 0.1524)
				(type default)
			)
			(layer "F.SilkS")
		)
		(fp_line
			(start -0.12065 -0.305054)
			(end -0.12065 -0.2794)
			(stroke
				(width 0.1)
				(type default)
			)
			(layer "F.Fab")
		)
		(fp_line
			(start -0.67945 -0.305054)
			(end -0.12065 -0.305054)
			(stroke
				(width 0.1)
				(type default)
			)
			(layer "F.Fab")
		)
		(fp_line
			(start 0.67945 -0.3048)
			(end 0.67945 0.3048)
			(stroke
				(width 0.1)
				(type default)
			)
			(layer "F.Fab")
		)
		(fp_line
			(start 0.12065 -0.3048)
			(end 0.67945 -0.3048)
			(stroke
				(width 0.1)
				(type default)
			)
			(layer "F.Fab")
		)
		(fp_line
			(start 0.12065 -0.2794)
			(end 0.12065 -0.3048)
			(stroke
				(width 0.1)
				(type default)
			)
			(layer "F.Fab")
		)
		(fp_line
			(start -0.12065 -0.2794)
			(end 0.12065 -0.2794)
			(stroke
				(width 0.1)
				(type default)
			)
			(layer "F.Fab")
		)
		(fp_line
			(start 0.120396 0.2794)
			(end -0.12065 0.2794)
			(stroke
				(width 0.1)
				(type default)
			)
			(layer "F.Fab")
		)
		(fp_line
			(start -0.12065 0.2794)
			(end -0.12065 0.3048)
			(stroke
				(width 0.1)
				(type default)
			)
			(layer "F.Fab")
		)
		(fp_line
			(start 0.67945 0.3048)
			(end 0.120396 0.3048)
			(stroke
				(width 0.1)
				(type default)
			)
			(layer "F.Fab")
		)
		(fp_line
			(start 0.120396 0.3048)
			(end 0.120396 0.2794)
			(stroke
				(width 0.1)
				(type default)
			)
			(layer "F.Fab")
		)
		(fp_line
			(start -0.12065 0.3048)
			(end -0.67945 0.3048)
			(stroke
				(width 0.1)
				(type default)
			)
			(layer "F.Fab")
		)
		(fp_line
			(start -0.67945 0.3048)
			(end -0.67945 -0.305054)
			(stroke
				(width 0.1)
				(type default)
			)
			(layer "F.Fab")
		)
		(pad "1" smd rect
			(at -0.40005 0 270)
			(size 0.4572 0.508)
			(layers "F.Cu" "F.Mask" "F.Paste")
			(net "FAN_7_FAULT_R")
		)
		(pad "2" smd rect
			(at 0.40005 0 270)
			(size 0.4572 0.508)
			(layers "F.Cu" "F.Mask" "F.Paste")
			(net "FAN_7_FAULT")
		)
	)
	(footprint ""
		(layer "F.Cu")
		(at 16.393922 -14.310868 -90)
		(property "Reference" "C2014"
			(at 0 0 270)
			(layer "F.SilkS")
			(hide yes)
			(effects
				(font
					(size 1.27 1.27)
				)
			)
		)
		(property "Value" ""
			(at 0 0 270)
			(layer "F.Fab")
			(effects
				(font
					(size 1.27 1.27)
				)
			)
		)
		(duplicate_pad_numbers_are_jumpers no)
		(fp_line
			(start -0.7874 0.4064)
			(end -0.7874 -0.4064)
			(stroke
				(width 0.1524)
				(type default)
			)
			(layer "F.SilkS")
		)
		(fp_line
			(start 0.7874 0.4064)
			(end -0.7874 0.4064)
			(stroke
				(width 0.1524)
				(type default)
			)
			(layer "F.SilkS")
		)
		(fp_line
			(start -0.7874 -0.4064)
			(end 0.7874 -0.4064)
			(stroke
				(width 0.1524)
				(type default)
			)
			(layer "F.SilkS")
		)
		(fp_line
			(start 0.7874 -0.4064)
			(end 0.7874 0.4064)
			(stroke
				(width 0.1524)
				(type default)
			)
			(layer "F.SilkS")
		)
		(fp_line
			(start -0.67945 0.3048)
			(end -0.67945 -0.305054)
			(stroke
				(width 0.1)
				(type default)
			)
			(layer "F.Fab")
		)
		(fp_line
			(start -0.12065 0.3048)
			(end -0.67945 0.3048)
			(stroke
				(width 0.1)
				(type default)
			)
			(layer "F.Fab")
		)
		(fp_line
			(start 0.120396 0.3048)
			(end 0.120396 0.2794)
			(stroke
				(width 0.1)
				(type default)
			)
			(layer "F.Fab")
		)
		(fp_line
			(start 0.67945 0.3048)
			(end 0.120396 0.3048)
			(stroke
				(width 0.1)
				(type default)
			)
			(layer "F.Fab")
		)
		(fp_line
			(start -0.12065 0.2794)
			(end -0.12065 0.3048)
			(stroke
				(width 0.1)
				(type default)
			)
			(layer "F.Fab")
		)
		(fp_line
			(start 0.120396 0.2794)
			(end -0.12065 0.2794)
			(stroke
				(width 0.1)
				(type default)
			)
			(layer "F.Fab")
		)
		(fp_line
			(start -0.12065 -0.2794)
			(end 0.12065 -0.2794)
			(stroke
				(width 0.1)
				(type default)
			)
			(layer "F.Fab")
		)
		(fp_line
			(start 0.12065 -0.2794)
			(end 0.12065 -0.3048)
			(stroke
				(width 0.1)
				(type default)
			)
			(layer "F.Fab")
		)
		(fp_line
			(start 0.12065 -0.3048)
			(end 0.67945 -0.3048)
			(stroke
				(width 0.1)
				(type default)
			)
			(layer "F.Fab")
		)
		(fp_line
			(start 0.67945 -0.3048)
			(end 0.67945 0.3048)
			(stroke
				(width 0.1)
				(type default)
			)
			(layer "F.Fab")
		)
		(fp_line
			(start -0.67945 -0.305054)
			(end -0.12065 -0.305054)
			(stroke
				(width 0.1)
				(type default)
			)
			(layer "F.Fab")
		)
		(fp_line
			(start -0.12065 -0.305054)
			(end -0.12065 -0.2794)
			(stroke
				(width 0.1)
				(type default)
			)
			(layer "F.Fab")
		)
		(pad "1" smd circle
			(at -0.40005 0 270)
			(size 0 0)
			(layers "F.Cu" "F.Mask" "F.Paste")
			(net "FAN_4_PWM_OL_R")
		)
		(pad "2" smd circle
			(at 0.40005 0 270)
			(size 0 0)
			(layers "F.Cu" "F.Mask" "F.Paste")
			(net "GND")
		)
	)
	(footprint ""
		(layer "F.Cu")
		(at 17.399 -26.924 180)
		(property "Reference" "U340"
			(at -0.254 1.75133 0)
			(unlocked yes)
			(layer "F.SilkS")
			(effects
				(font
					(size 0.7874 0.5842)
					(thickness 0.1524)
				)
				(justify left)
			)
		)
		(property "Value" ""
			(at 0 0 180)
			(layer "F.Fab")
			(effects
				(font
					(size 1.27 1.27)
				)
			)
		)
		(duplicate_pad_numbers_are_jumpers no)
		(fp_line
			(start 1.335278 1.100074)
			(end 1.335278 -1.100074)
			(stroke
				(width 0.1524)
				(type default)
			)
			(layer "F.SilkS")
		)
		(fp_line
			(start 1.335278 -1.100074)
			(end -1.335278 -1.100074)
			(stroke
				(width 0.1524)
				(type default)
			)
			(layer "F.SilkS")
		)
		(fp_line
			(start -1.335278 1.100074)
			(end 1.335278 1.100074)
			(stroke
				(width 0.1524)
				(type default)
			)
			(layer "F.SilkS")
		)
		(fp_line
			(start -1.335278 -1.100074)
			(end -1.335278 1.100074)
			(stroke
				(width 0.1524)
				(type default)
			)
			(layer "F.SilkS")
		)
		(fp_line
			(start 0.674878 1.100074)
			(end 0.674878 -1.100074)
			(stroke
				(width 0.1)
				(type default)
			)
			(layer "F.Fab")
		)
		(fp_line
			(start 0.674878 -1.100074)
			(end -0.674878 -1.100074)
			(stroke
				(width 0.1)
				(type default)
			)
			(layer "F.Fab")
		)
		(fp_line
			(start -0.674878 1.100074)
			(end 0.674878 1.100074)
			(stroke
				(width 0.1)
				(type default)
			)
			(layer "F.Fab")
		)
		(fp_line
			(start -0.674878 -1.100074)
			(end -0.674878 1.100074)
			(stroke
				(width 0.1)
				(type default)
			)
			(layer "F.Fab")
		)
		(pad "D" smd rect
			(at 0.8001 0 90)
			(size 0.6096 0.8128)
			(layers "F.Cu" "F.Mask" "F.Paste")
			(net "FAN_4_OK_LED_R_N")
		)
		(pad "G" smd rect
			(at -0.8001 -0.649986 90)
			(size 0.6096 0.8128)
			(layers "F.Cu" "F.Mask" "F.Paste")
			(net "FAN_4_OK_R_LED")
		)
		(pad "S" smd rect
			(at -0.8001 0.649986 90)
			(size 0.6096 0.8128)
			(layers "F.Cu" "F.Mask" "F.Paste")
			(net "GND")
		)
	)
)
